(kicad_pcb
	(version 20260206)
	(generator "pcbnew")
	(generator_version "10.0")
	(general
		(thickness 1.6)
		(legacy_teardrops no)
	)
	(paper "A4")
	(title_block
		(title "peb — Lightning_PEB_BRD.brd")
		(comment 1 "Lightning (Wiwynn / Facebook NVMe JBOF) / footprints 1-7 of 2563")
	)
	(layers
		(0 "F.Cu" signal "TOP")
		(4 "In1.Cu" signal "L2GND")
		(6 "In2.Cu" signal "L3")
		(8 "In3.Cu" signal "L4VCC")
		(10 "In4.Cu" signal "L5VCC")
		(12 "In5.Cu" signal "L6")
		(14 "In6.Cu" signal "L7GND")
		(2 "B.Cu" signal "BOTTOM")
		(9 "F.Adhes" user "F.Adhesive")
		(11 "B.Adhes" user "B.Adhesive")
		(13 "F.Paste" user "Package Geometry/Pastemask Top")
		(15 "B.Paste" user "Package Geometry/Pastemask Bottom")
		(5 "F.SilkS" user "Ref Des/Silkscreen Top")
		(7 "B.SilkS" user "Ref Des/Silkscreen Bottom")
		(1 "F.Mask" user "Board Geometry/Soldermask Top")
		(3 "B.Mask" user "Board Geometry/Soldermask Bottom")
		(17 "Dwgs.User" user "User.Drawings")
		(19 "Cmts.User" user "User.Comments")
		(21 "Eco1.User" user "User.Eco1")
		(23 "Eco2.User" user "User.Eco2")
		(25 "Edge.Cuts" user "Board Geometry/Outline")
		(27 "Margin" user)
		(31 "F.CrtYd" user "Package Geometry/Place Bound Top")
		(29 "B.CrtYd" user "Package Geometry/Place Bound Bottom")
		(35 "F.Fab" user "Ref Des/Assembly Top")
		(33 "B.Fab" user "Ref Des/Assembly Bottom")
	)
	(footprint ""
		(layer "F.Cu")
		(at 20.642326 -131.34086 90)
		(property "Reference" "R357"
			(at 0 0 90)
			(layer "F.SilkS")
			(hide yes)
			(effects
				(font
					(size 1.27 1.27)
				)
			)
		)
		(property "Value" "3K3R2F-2-GP"
			(at 0.064008 -3.993896 90)
			(unlocked yes)
			(layer "F.Fab")
			(hide yes)
			(effects
				(font
					(size 1.016 1.016)
					(thickness 0.1524)
				)
			)
		)
		(property "Device Type" "R402H16"
			(at 0.064008 -5.517896 90)
			(unlocked yes)
			(layer "F.Fab")
			(hide yes)
			(effects
				(font
					(size 1.016 1.016)
					(thickness 0.1524)
				)
			)
		)
		(duplicate_pad_numbers_are_jumpers no)
		(fp_line
			(start 0.508 -0.9398)
			(end -0.508 -0.9398)
			(stroke
				(width 0.1524)
				(type default)
			)
			(layer "F.SilkS")
		)
		(fp_line
			(start -0.508 -0.9398)
			(end -0.508 0.9398)
			(stroke
				(width 0.1524)
				(type default)
			)
			(layer "F.SilkS")
		)
		(fp_rect
			(start -0.508 0.9398)
			(end 0.508 -0.9398)
			(stroke
				(width 0)
				(type default)
			)
			(fill no)
			(layer "F.CrtYd")
		)
		(fp_rect
			(start -0.508 0.9398)
			(end 0.508 -0.9398)
			(stroke
				(width 0)
				(type default)
			)
			(fill no)
			(layer "F.Fab")
		)
		(pad "1" smd custom
			(at 0 -0.4445 90)
			(size 0.1397 0.1397)
			(layers "F.Cu" "F.Mask" "F.Paste")
			(net "P3V3_STBY")
			(options
				(clearance outline)
				(anchor circle)
			)
			(primitives
				(gr_poly
					(pts
						(arc
							(start -0.1778 -0.2794)
							(mid -0.249642 -0.249642)
							(end -0.2794 -0.1778)
						)
						(arc
							(start -0.2794 0.1778)
							(mid -0.249642 0.249642)
							(end -0.1778 0.2794)
						)
						(arc
							(start 0.1778 0.2794)
							(mid 0.249642 0.249642)
							(end 0.2794 0.1778)
						)
						(arc
							(start 0.2794 -0.1778)
							(mid 0.249642 -0.249642)
							(end 0.1778 -0.2794)
						)
					)
					(width 0)
					(fill yes)
				)
			)
		)
		(pad "2" smd custom
			(at 0 0.4445 90)
			(size 0.1397 0.1397)
			(layers "F.Cu" "F.Mask" "F.Paste")
			(net "ROMA20")
			(options
				(clearance outline)
				(anchor circle)
			)
			(primitives
				(gr_poly
					(pts
						(arc
							(start -0.1778 -0.2794)
							(mid -0.249642 -0.249642)
							(end -0.2794 -0.1778)
						)
						(arc
							(start -0.2794 0.1778)
							(mid -0.249642 0.249642)
							(end -0.1778 0.2794)
						)
						(arc
							(start 0.1778 0.2794)
							(mid 0.249642 0.249642)
							(end 0.2794 0.1778)
						)
						(arc
							(start 0.2794 -0.1778)
							(mid 0.249642 -0.249642)
							(end 0.1778 -0.2794)
						)
					)
					(width 0)
					(fill yes)
				)
			)
		)
	)
	(footprint ""
		(layer "F.Cu")
		(at 205.3844 -25.0698 90)
		(property "Reference" "R2968"
			(at 0 0 90)
			(layer "F.SilkS")
			(hide yes)
			(effects
				(font
					(size 1.27 1.27)
				)
			)
		)
		(property "Value" "0R2J-2-GP"
			(at 0.064008 -3.993896 90)
			(unlocked yes)
			(layer "F.Fab")
			(hide yes)
			(effects
				(font
					(size 1.016 1.016)
					(thickness 0.1524)
				)
			)
		)
		(property "Device Type" "R402H16"
			(at 0.064008 -5.517896 90)
			(unlocked yes)
			(layer "F.Fab")
			(hide yes)
			(effects
				(font
					(size 1.016 1.016)
					(thickness 0.1524)
				)
			)
		)
		(duplicate_pad_numbers_are_jumpers no)
		(fp_line
			(start 0.508 -0.9398)
			(end -0.508 -0.9398)
			(stroke
				(width 0.1524)
				(type default)
			)
			(layer "F.SilkS")
		)
		(fp_line
			(start -0.508 -0.9398)
			(end -0.508 0.9398)
			(stroke
				(width 0.1524)
				(type default)
			)
			(layer "F.SilkS")
		)
		(fp_rect
			(start -0.508 0.9398)
			(end 0.508 -0.9398)
			(stroke
				(width 0)
				(type default)
			)
			(fill no)
			(layer "F.CrtYd")
		)
		(fp_rect
			(start -0.508 0.9398)
			(end 0.508 -0.9398)
			(stroke
				(width 0)
				(type default)
			)
			(fill no)
			(layer "F.Fab")
		)
		(pad "1" smd custom
			(at 0 -0.4445 90)
			(size 0.1397 0.1397)
			(layers "F.Cu" "F.Mask" "F.Paste")
			(net "U56_SDA")
			(options
				(clearance outline)
				(anchor circle)
			)
			(primitives
				(gr_poly
					(pts
						(arc
							(start -0.1778 -0.2794)
							(mid -0.249642 -0.249642)
							(end -0.2794 -0.1778)
						)
						(arc
							(start -0.2794 0.1778)
							(mid -0.249642 0.249642)
							(end -0.1778 0.2794)
						)
						(arc
							(start 0.1778 0.2794)
							(mid 0.249642 0.249642)
							(end 0.2794 0.1778)
						)
						(arc
							(start 0.2794 -0.1778)
							(mid 0.249642 -0.249642)
							(end 0.1778 -0.2794)
						)
					)
					(width 0)
					(fill yes)
				)
			)
		)
		(pad "2" smd custom
			(at 0 0.4445 90)
			(size 0.1397 0.1397)
			(layers "F.Cu" "F.Mask" "F.Paste")
			(net "BMC_I2C8_CLKBUF1_SDA")
			(options
				(clearance outline)
				(anchor circle)
			)
			(primitives
				(gr_poly
					(pts
						(arc
							(start -0.1778 -0.2794)
							(mid -0.249642 -0.249642)
							(end -0.2794 -0.1778)
						)
						(arc
							(start -0.2794 0.1778)
							(mid -0.249642 0.249642)
							(end -0.1778 0.2794)
						)
						(arc
							(start 0.1778 0.2794)
							(mid 0.249642 0.249642)
							(end 0.2794 0.1778)
						)
						(arc
							(start 0.2794 -0.1778)
							(mid 0.249642 -0.249642)
							(end 0.1778 -0.2794)
						)
					)
					(width 0)
					(fill yes)
				)
			)
		)
	)
	(footprint ""
		(layer "F.Cu")
		(at 204.208126 -212.420454 180)
		(property "Reference" "C114"
			(at 0 0 180)
			(layer "F.SilkS")
			(hide yes)
			(effects
				(font
					(size 1.27 1.27)
				)
			)
		)
		(property "Value" "SCD22U10V2KX-1GP"
			(at 1.1811 -2.7051 180)
			(unlocked yes)
			(layer "F.Fab")
			(hide yes)
			(effects
				(font
					(size 1.016 1.016)
					(thickness 0.1524)
				)
			)
		)
		(property "Device Type" "C402H22"
			(at 1.1811 -4.2291 180)
			(unlocked yes)
			(layer "F.Fab")
			(hide yes)
			(effects
				(font
					(size 1.016 1.016)
					(thickness 0.1524)
				)
			)
		)
		(duplicate_pad_numbers_are_jumpers no)
		(fp_rect
			(start -0.4318 0.9525)
			(end 0.4318 -0.9525)
			(stroke
				(width 0)
				(type default)
			)
			(fill no)
			(layer "F.CrtYd")
		)
		(fp_rect
			(start -0.4318 0.9525)
			(end 0.4318 -0.9525)
			(stroke
				(width 0)
				(type default)
			)
			(fill no)
			(layer "F.Fab")
		)
		(pad "1" smd custom
			(at 0 -0.4445 180)
			(size 0.1524 0.1524)
			(layers "F.Cu" "F.Mask" "F.Paste")
			(net "PCIE_TX_CAP_N41")
			(options
				(clearance outline)
				(anchor circle)
			)
			(primitives
				(gr_poly
					(pts
						(arc
							(start 0.3048 -0.2032)
							(mid 0.275042 -0.275042)
							(end 0.2032 -0.3048)
						)
						(arc
							(start -0.2032 -0.3048)
							(mid -0.275042 -0.275042)
							(end -0.3048 -0.2032)
						)
						(arc
							(start -0.3048 0.2032)
							(mid -0.275042 0.275042)
							(end -0.2032 0.3048)
						)
						(arc
							(start 0.2032 0.3048)
							(mid 0.275042 0.275042)
							(end 0.3048 0.2032)
						)
					)
					(width 0)
					(fill yes)
				)
			)
		)
		(pad "2" smd custom
			(at 0 0.4445 180)
			(size 0.1524 0.1524)
			(layers "F.Cu" "F.Mask" "F.Paste")
			(net "PCIE_TX_N41")
			(options
				(clearance outline)
				(anchor circle)
			)
			(primitives
				(gr_poly
					(pts
						(arc
							(start 0.3048 -0.2032)
							(mid 0.275042 -0.275042)
							(end 0.2032 -0.3048)
						)
						(arc
							(start -0.2032 -0.3048)
							(mid -0.275042 -0.275042)
							(end -0.3048 -0.2032)
						)
						(arc
							(start -0.3048 0.2032)
							(mid -0.275042 0.275042)
							(end -0.2032 0.3048)
						)
						(arc
							(start 0.2032 0.3048)
							(mid 0.275042 0.275042)
							(end 0.3048 0.2032)
						)
					)
					(width 0)
					(fill yes)
				)
			)
		)
	)
	(footprint ""
		(layer "F.Cu")
		(at 310.374792 -33.555686)
		(property "Reference" "C19"
			(at 0 0 0)
			(layer "F.SilkS")
			(hide yes)
			(effects
				(font
					(size 1.27 1.27)
				)
			)
		)
		(property "Value" "SCD22U10V2KX-1GP"
			(at 1.1811 -2.7051 0)
			(unlocked yes)
			(layer "F.Fab")
			(hide yes)
			(effects
				(font
					(size 1.016 1.016)
					(thickness 0.1524)
				)
			)
		)
		(property "Device Type" "C402H22"
			(at 1.1811 -4.2291 0)
			(unlocked yes)
			(layer "F.Fab")
			(hide yes)
			(effects
				(font
					(size 1.016 1.016)
					(thickness 0.1524)
				)
			)
		)
		(duplicate_pad_numbers_are_jumpers no)
		(fp_rect
			(start -0.4318 0.9525)
			(end 0.4318 -0.9525)
			(stroke
				(width 0)
				(type default)
			)
			(fill no)
			(layer "F.CrtYd")
		)
		(fp_rect
			(start -0.4318 0.9525)
			(end 0.4318 -0.9525)
			(stroke
				(width 0)
				(type default)
			)
			(fill no)
			(layer "F.Fab")
		)
		(pad "1" smd custom
			(at 0 -0.4445)
			(size 0.1524 0.1524)
			(layers "F.Cu" "F.Mask" "F.Paste")
			(net "PCIE_TX_CAP_P9")
			(options
				(clearance outline)
				(anchor circle)
			)
			(primitives
				(gr_poly
					(pts
						(arc
							(start 0.3048 -0.2032)
							(mid 0.275042 -0.275042)
							(end 0.2032 -0.3048)
						)
						(arc
							(start -0.2032 -0.3048)
							(mid -0.275042 -0.275042)
							(end -0.3048 -0.2032)
						)
						(arc
							(start -0.3048 0.2032)
							(mid -0.275042 0.275042)
							(end -0.2032 0.3048)
						)
						(arc
							(start 0.2032 0.3048)
							(mid 0.275042 0.275042)
							(end 0.3048 0.2032)
						)
					)
					(width 0)
					(fill yes)
				)
			)
		)
		(pad "2" smd custom
			(at 0 0.4445)
			(size 0.1524 0.1524)
			(layers "F.Cu" "F.Mask" "F.Paste")
			(net "PCIE_TX_P9")
			(options
				(clearance outline)
				(anchor circle)
			)
			(primitives
				(gr_poly
					(pts
						(arc
							(start 0.3048 -0.2032)
							(mid 0.275042 -0.275042)
							(end 0.2032 -0.3048)
						)
						(arc
							(start -0.2032 -0.3048)
							(mid -0.275042 -0.275042)
							(end -0.3048 -0.2032)
						)
						(arc
							(start -0.3048 0.2032)
							(mid -0.275042 0.275042)
							(end -0.2032 0.3048)
						)
						(arc
							(start 0.2032 0.3048)
							(mid 0.275042 0.275042)
							(end 0.3048 0.2032)
						)
					)
					(width 0)
					(fill yes)
				)
			)
		)
	)
	(footprint ""
		(layer "F.Cu")
		(at 53.756052 -110.19663 90)
		(property "Reference" "U37"
			(at 0 0 90)
			(layer "F.SilkS")
			(hide yes)
			(effects
				(font
					(size 1.27 1.27)
				)
			)
		)
		(property "Value" "2N7002DW-7F-GP"
			(at -2.3622 -8.2042 90)
			(unlocked yes)
			(layer "F.Fab")
			(hide yes)
			(effects
				(font
					(size 1.016 1.016)
					(thickness 0.1524)
				)
			)
		)
		(property "Device Type" "SOT-363H44"
			(at -2.3622 -10.1092 90)
			(unlocked yes)
			(layer "F.Fab")
			(hide yes)
			(effects
				(font
					(size 1.016 1.016)
					(thickness 0.1524)
				)
			)
		)
		(duplicate_pad_numbers_are_jumpers no)
		(fp_line
			(start 1.4478 -1.7018)
			(end -1.4478 -1.7018)
			(stroke
				(width 0.1524)
				(type default)
			)
			(layer "F.SilkS")
		)
		(fp_line
			(start -1.4478 -1.7018)
			(end -1.4478 1.7018)
			(stroke
				(width 0.1524)
				(type default)
			)
			(layer "F.SilkS")
		)
		(fp_line
			(start -1.27 1.524)
			(end -1.27 0.6604)
			(stroke
				(width 0.4826)
				(type default)
			)
			(layer "F.SilkS")
		)
		(fp_line
			(start 1.4478 1.7018)
			(end 1.4478 -1.7018)
			(stroke
				(width 0.1524)
				(type default)
			)
			(layer "F.SilkS")
		)
		(fp_line
			(start -1.4478 1.7018)
			(end 1.4478 1.7018)
			(stroke
				(width 0.1524)
				(type default)
			)
			(layer "F.SilkS")
		)
		(fp_poly
			(pts
				(xy -1.524 -1.778) (xy 1.524 -1.778) (xy 1.524 1.778) (xy -1.524 1.778)
			)
			(stroke
				(width 0)
				(type default)
			)
			(fill no)
			(layer "F.CrtYd")
		)
		(fp_poly
			(pts
				(xy -1.524 -1.778) (xy 1.524 -1.778) (xy 1.524 1.778) (xy -1.524 1.778)
			)
			(stroke
				(width 0)
				(type default)
			)
			(fill no)
			(layer "F.Fab")
		)
		(pad "1" smd rect
			(at -0.65024 0.9398 90)
			(size 0.4064 1.016)
			(layers "F.Cu" "F.Mask" "F.Paste")
			(net "BMC_I2C13_MINI7_SCL_S")
		)
		(pad "2" smd rect
			(at 0 0.9398 90)
			(size 0.4064 1.016)
			(layers "F.Cu" "F.Mask" "F.Paste")
			(net "I2C7_LS_G2")
		)
		(pad "3" smd rect
			(at 0.65024 0.9398 90)
			(size 0.4064 1.016)
			(layers "F.Cu" "F.Mask" "F.Paste")
			(net "BMC_I2C13_MINI7_SDA")
		)
		(pad "4" smd rect
			(at 0.65024 -0.9398 90)
			(size 0.4064 1.016)
			(layers "F.Cu" "F.Mask" "F.Paste")
			(net "BMC_I2C13_MINI7_SDA_S")
		)
		(pad "5" smd rect
			(at 0 -0.9398 90)
			(size 0.4064 1.016)
			(layers "F.Cu" "F.Mask" "F.Paste")
			(net "I2C7_LS_G1")
		)
		(pad "6" smd rect
			(at -0.65024 -0.9398 90)
			(size 0.4064 1.016)
			(layers "F.Cu" "F.Mask" "F.Paste")
			(net "BMC_I2C13_MINI7_SCL")
		)
	)
	(footprint ""
		(layer "F.Cu")
		(at 316.606936 -36.885118 90)
		(property "Reference" "R254"
			(at 0 0 90)
			(layer "F.SilkS")
			(hide yes)
			(effects
				(font
					(size 1.27 1.27)
				)
			)
		)
		(property "Value" "4K7R2F-GP"
			(at 0.064008 -3.993896 90)
			(unlocked yes)
			(layer "F.Fab")
			(hide yes)
			(effects
				(font
					(size 1.016 1.016)
					(thickness 0.1524)
				)
			)
		)
		(property "Device Type" "R402H16"
			(at 0.064008 -5.517896 90)
			(unlocked yes)
			(layer "F.Fab")
			(hide yes)
			(effects
				(font
					(size 1.016 1.016)
					(thickness 0.1524)
				)
			)
		)
		(duplicate_pad_numbers_are_jumpers no)
		(fp_line
			(start 0.508 -0.9398)
			(end -0.508 -0.9398)
			(stroke
				(width 0.1524)
				(type default)
			)
			(layer "F.SilkS")
		)
		(fp_line
			(start -0.508 -0.9398)
			(end -0.508 0.9398)
			(stroke
				(width 0.1524)
				(type default)
			)
			(layer "F.SilkS")
		)
		(fp_rect
			(start -0.508 0.9398)
			(end 0.508 -0.9398)
			(stroke
				(width 0)
				(type default)
			)
			(fill no)
			(layer "F.CrtYd")
		)
		(fp_rect
			(start -0.508 0.9398)
			(end 0.508 -0.9398)
			(stroke
				(width 0)
				(type default)
			)
			(fill no)
			(layer "F.Fab")
		)
		(pad "1" smd custom
			(at 0 -0.4445 90)
			(size 0.1397 0.1397)
			(layers "F.Cu" "F.Mask" "F.Paste")
			(net "P3V3_STBY")
			(options
				(clearance outline)
				(anchor circle)
			)
			(primitives
				(gr_poly
					(pts
						(arc
							(start -0.1778 -0.2794)
							(mid -0.249642 -0.249642)
							(end -0.2794 -0.1778)
						)
						(arc
							(start -0.2794 0.1778)
							(mid -0.249642 0.249642)
							(end -0.1778 0.2794)
						)
						(arc
							(start 0.1778 0.2794)
							(mid 0.249642 0.249642)
							(end 0.2794 0.1778)
						)
						(arc
							(start 0.2794 -0.1778)
							(mid 0.249642 -0.249642)
							(end 0.1778 -0.2794)
						)
					)
					(width 0)
					(fill yes)
				)
			)
		)
		(pad "2" smd custom
			(at 0 0.4445 90)
			(size 0.1397 0.1397)
			(layers "F.Cu" "F.Mask" "F.Paste")
			(net "CLK_P_8_R")
			(options
				(clearance outline)
				(anchor circle)
			)
			(primitives
				(gr_poly
					(pts
						(arc
							(start -0.1778 -0.2794)
							(mid -0.249642 -0.249642)
							(end -0.2794 -0.1778)
						)
						(arc
							(start -0.2794 0.1778)
							(mid -0.249642 0.249642)
							(end -0.1778 0.2794)
						)
						(arc
							(start 0.1778 0.2794)
							(mid 0.249642 0.249642)
							(end 0.2794 0.1778)
						)
						(arc
							(start 0.2794 -0.1778)
							(mid 0.249642 -0.249642)
							(end 0.1778 -0.2794)
						)
					)
					(width 0)
					(fill yes)
				)
			)
		)
	)
	(footprint ""
		(layer "F.Cu")
		(at 26.0604 -77.9018 90)
		(property "Reference" "C632"
			(at 0 0 90)
			(layer "F.SilkS")
			(hide yes)
			(effects
				(font
					(size 1.27 1.27)
				)
			)
		)
		(property "Value" "SCD1U16V2KX-3GP"
			(at 1.1811 -2.7051 90)
			(unlocked yes)
			(layer "F.Fab")
			(hide yes)
			(effects
				(font
					(size 1.016 1.016)
					(thickness 0.1524)
				)
			)
		)
		(property "Device Type" "C402H22"
			(at 1.1811 -4.2291 90)
			(unlocked yes)
			(layer "F.Fab")
			(hide yes)
			(effects
				(font
					(size 1.016 1.016)
					(thickness 0.1524)
				)
			)
		)
		(duplicate_pad_numbers_are_jumpers no)
		(fp_rect
			(start -0.4318 0.9525)
			(end 0.4318 -0.9525)
			(stroke
				(width 0)
				(type default)
			)
			(fill no)
			(layer "F.CrtYd")
		)
		(fp_rect
			(start -0.4318 0.9525)
			(end 0.4318 -0.9525)
			(stroke
				(width 0)
				(type default)
			)
			(fill no)
			(layer "F.Fab")
		)
		(pad "1" smd custom
			(at 0 -0.4445 90)
			(size 0.1524 0.1524)
			(layers "F.Cu" "F.Mask" "F.Paste")
			(net "P3V3_STBY")
			(options
				(clearance outline)
				(anchor circle)
			)
			(primitives
				(gr_poly
					(pts
						(arc
							(start 0.3048 -0.2032)
							(mid 0.275042 -0.275042)
							(end 0.2032 -0.3048)
						)
						(arc
							(start -0.2032 -0.3048)
							(mid -0.275042 -0.275042)
							(end -0.3048 -0.2032)
						)
						(arc
							(start -0.3048 0.2032)
							(mid -0.275042 0.275042)
							(end -0.2032 0.3048)
						)
						(arc
							(start 0.2032 0.3048)
							(mid 0.275042 0.275042)
							(end 0.3048 0.2032)
						)
					)
					(width 0)
					(fill yes)
				)
			)
		)
		(pad "2" smd custom
			(at 0 0.4445 90)
			(size 0.1524 0.1524)
			(layers "F.Cu" "F.Mask" "F.Paste")
			(net "GND")
			(options
				(clearance outline)
				(anchor circle)
			)
			(primitives
				(gr_poly
					(pts
						(arc
							(start 0.3048 -0.2032)
							(mid 0.275042 -0.275042)
							(end 0.2032 -0.3048)
						)
						(arc
							(start -0.2032 -0.3048)
							(mid -0.275042 -0.275042)
							(end -0.3048 -0.2032)
						)
						(arc
							(start -0.3048 0.2032)
							(mid -0.275042 0.275042)
							(end -0.2032 0.3048)
						)
						(arc
							(start 0.2032 0.3048)
							(mid 0.275042 0.275042)
							(end 0.3048 0.2032)
						)
					)
					(width 0)
					(fill yes)
				)
			)
		)
	)
)
